(kicad_pcb
	(version 20260206)
	(generator "pcbnew")
	(generator_version "10.0")
	(general
		(thickness 1.21888)
		(legacy_teardrops no)
	)
	(paper "A4")
	(title_block
		(title "timecard-beta-v1 — TimeCard-DC-V1.PcbDoc")
		(comment 1 "Time Appliance Project (Time Card) / footprint 22 of 120 (P1), pads 134-268 of 340")
	)
	(layers
		(0 "F.Cu" signal "TOP")
		(4 "In1.Cu" signal "SGND")
		(6 "In2.Cu" signal "IN1")
		(8 "In3.Cu" signal "IN2")
		(10 "In4.Cu" signal "SGND1")
		(2 "B.Cu" signal "BOTTOM")
		(9 "F.Adhes" user "F.Adhesive")
		(11 "B.Adhes" user "B.Adhesive")
		(13 "F.Paste" user "Top Paste")
		(15 "B.Paste" user "Bottom Paste")
		(5 "F.SilkS" user "Top Overlay")
		(7 "B.SilkS" user "Bottom Overlay")
		(1 "F.Mask" user "Top Solder")
		(3 "B.Mask" user "Bottom Solder")
		(17 "Dwgs.User" user "User.Drawings")
		(19 "Cmts.User" user "User.Comments")
		(21 "Eco1.User" user "User.Eco1")
		(23 "Eco2.User" user "User.Eco2")
		(25 "Edge.Cuts" user)
		(27 "Margin" user)
		(31 "F.CrtYd" user "Top Courtyard")
		(29 "B.CrtYd" user "Bottom Courtyard")
		(35 "F.Fab" user "Top Component Center")
		(33 "B.Fab" user "Bottom Component Center")
	)
	(footprint "FPGA_CONN:FPGA_CONN"
		(locked yes)
		(layer "F.Cu")
		(at 125.389655 117.4386)
		(property "Reference" "P1"
			(at -27.35726 -23.265455 0)
			(unlocked yes)
			(layer "F.SilkS")
			(effects
				(font
					(size 0.762 0.762)
					(thickness 0.2286)
				)
				(justify left bottom)
			)
		)
		(property "Value" "FPGA_CONN"
			(at -43.9575 52.70297 0)
			(unlocked yes)
			(layer "F.SilkS")
			(hide yes)
			(effects
				(font
					(size 1.524 1.524)
					(thickness 0.254)
				)
				(justify left bottom)
			)
		)
		(sheetname "FPGA")
		(sheetfile "FPGA.kicad_sch")
		(duplicate_pad_numbers_are_jumpers no)
		(pad "B-50" smd rect
			(at 1.29857 -20.82013)
			(size 0.24994 1.54991)
			(layers "F.Cu" "F.Mask" "F.Paste")
			(net "GND")
		)
		(pad "B-51" smd rect
			(at 1.7987 -16.77035)
			(size 0.24994 1.54991)
			(layers "F.Cu" "F.Mask" "F.Paste")
		)
		(pad "B-52" smd rect
			(at 1.7987 -20.82013)
			(size 0.24994 1.54991)
			(layers "F.Cu" "F.Mask" "F.Paste")
		)
		(pad "B-53" smd rect
			(at 2.29857 -16.77035)
			(size 0.24994 1.54991)
			(layers "F.Cu" "F.Mask" "F.Paste")
			(net "FPGA_MAC_PPS_IN1-")
		)
		(pad "B-54" smd rect
			(at 2.29857 -20.82013)
			(size 0.24994 1.54991)
			(layers "F.Cu" "F.Mask" "F.Paste")
		)
		(pad "B-55" smd rect
			(at 2.7987 -16.77035)
			(size 0.24994 1.54991)
			(layers "F.Cu" "F.Mask" "F.Paste")
		)
		(pad "B-56" smd rect
			(at 2.7987 -20.82013)
			(size 0.24994 1.54991)
			(layers "F.Cu" "F.Mask" "F.Paste")
		)
		(pad "B-57" smd rect
			(at 3.29857 -16.77035)
			(size 0.24994 1.54991)
			(layers "F.Cu" "F.Mask" "F.Paste")
		)
		(pad "B-58" smd rect
			(at 3.29857 -20.82013)
			(size 0.24994 1.54991)
			(layers "F.Cu" "F.Mask" "F.Paste")
		)
		(pad "B-59" smd rect
			(at 3.7987 -16.77035)
			(size 0.24994 1.54991)
			(layers "F.Cu" "F.Mask" "F.Paste")
			(net "GND")
		)
		(pad "B-60" smd rect
			(at 3.7987 -20.82013)
			(size 0.24994 1.54991)
			(layers "F.Cu" "F.Mask" "F.Paste")
			(net "GND")
		)
		(pad "B-61" smd rect
			(at 4.29857 -16.77035)
			(size 0.24994 1.54991)
			(layers "F.Cu" "F.Mask" "F.Paste")
			(net "SDA")
		)
		(pad "B-62" smd rect
			(at 4.29857 -20.82013)
			(size 0.24994 1.54991)
			(layers "F.Cu" "F.Mask" "F.Paste")
		)
		(pad "B-63" smd rect
			(at 4.79869 -16.77035)
			(size 0.24994 1.54991)
			(layers "F.Cu" "F.Mask" "F.Paste")
		)
		(pad "B-64" smd rect
			(at 4.79869 -20.82013)
			(size 0.24994 1.54991)
			(layers "F.Cu" "F.Mask" "F.Paste")
		)
		(pad "B-65" smd rect
			(at 5.29857 -16.77035)
			(size 0.24994 1.54991)
			(layers "F.Cu" "F.Mask" "F.Paste")
		)
		(pad "B-66" smd rect
			(at 5.29857 -20.82013)
			(size 0.24994 1.54991)
			(layers "F.Cu" "F.Mask" "F.Paste")
		)
		(pad "B-67" smd rect
			(at 5.79869 -16.77035)
			(size 0.24994 1.54991)
			(layers "F.Cu" "F.Mask" "F.Paste")
			(net "SCL")
		)
		(pad "B-68" smd rect
			(at 5.79869 -20.82013)
			(size 0.24994 1.54991)
			(layers "F.Cu" "F.Mask" "F.Paste")
		)
		(pad "B-69" smd rect
			(at 6.29856 -16.77035)
			(size 0.24994 1.54991)
			(layers "F.Cu" "F.Mask" "F.Paste")
			(net "GND")
		)
		(pad "B-70" smd rect
			(at 6.29856 -20.82013)
			(size 0.24994 1.54991)
			(layers "F.Cu" "F.Mask" "F.Paste")
			(net "GND")
		)
		(pad "B-71" smd rect
			(at 6.79869 -16.77035)
			(size 0.24994 1.54991)
			(layers "F.Cu" "F.Mask" "F.Paste")
		)
		(pad "B-72" smd rect
			(at 6.79869 -20.82013)
			(size 0.24994 1.54991)
			(layers "F.Cu" "F.Mask" "F.Paste")
			(net "MAC_USB+")
		)
		(pad "B-73" smd rect
			(at 7.29856 -16.77035)
			(size 0.24994 1.54991)
			(layers "F.Cu" "F.Mask" "F.Paste")
		)
		(pad "B-74" smd rect
			(at 7.29856 -20.82013)
			(size 0.24994 1.54991)
			(layers "F.Cu" "F.Mask" "F.Paste")
			(net "MAC_USB-")
		)
		(pad "B-75" smd rect
			(at 7.79869 -16.77035)
			(size 0.24994 1.54991)
			(layers "F.Cu" "F.Mask" "F.Paste")
		)
		(pad "B-76" smd rect
			(at 7.79869 -20.82013)
			(size 0.24994 1.54991)
			(layers "F.Cu" "F.Mask" "F.Paste")
		)
		(pad "B-77" smd rect
			(at 8.29856 -16.77035)
			(size 0.24994 1.54991)
			(layers "F.Cu" "F.Mask" "F.Paste")
		)
		(pad "B-78" smd rect
			(at 8.29856 -20.82013)
			(size 0.24994 1.54991)
			(layers "F.Cu" "F.Mask" "F.Paste")
		)
		(pad "B-79" smd rect
			(at 8.79869 -16.77035)
			(size 0.24994 1.54991)
			(layers "F.Cu" "F.Mask" "F.Paste")
			(net "GPS1_RX")
		)
		(pad "B-80" smd rect
			(at 8.79869 -20.82013)
			(size 0.24994 1.54991)
			(layers "F.Cu" "F.Mask" "F.Paste")
			(net "GPS1_TX")
		)
		(pad "B-81" smd rect
			(at -12.125 -18.8)
			(size 1.35001 1.70002)
			(layers "F.Cu" "F.Mask" "F.Paste")
		)
		(pad "B-82" thru_hole circle
			(at -10.95134 -18.79524)
			(size 0.55016 0.55016)
			(drill 0.55016)
			(layers "*.Cu" "*.Mask")
			(remove_unused_layers no)
			(thermal_bridge_angle 90)
		)
		(pad "B-83" thru_hole circle
			(at 9.04862 -18.79524)
			(size 0.55016 0.55016)
			(drill 0.55016)
			(layers "*.Cu" "*.Mask")
			(remove_unused_layers no)
			(thermal_bridge_angle 90)
		)
		(pad "B-84" smd rect
			(at 10.225 -18.8)
			(size 1.35001 1.70002)
			(layers "F.Cu" "F.Mask" "F.Paste")
		)
		(pad "C-1" smd rect
			(at -21.78647 9.62381)
			(size 1.54991 0.24994)
			(layers "F.Cu" "F.Mask" "F.Paste")
		)
		(pad "C-2" smd rect
			(at -25.83625 9.62381)
			(size 1.54991 0.24994)
			(layers "F.Cu" "F.Mask" "F.Paste")
		)
		(pad "C-3" smd rect
			(at -21.78647 9.12368)
			(size 1.54991 0.24994)
			(layers "F.Cu" "F.Mask" "F.Paste")
		)
		(pad "C-4" smd rect
			(at -25.83625 9.12368)
			(size 1.54991 0.24994)
			(layers "F.Cu" "F.Mask" "F.Paste")
		)
		(pad "C-5" smd rect
			(at -21.78647 8.62381)
			(size 1.54991 0.24994)
			(layers "F.Cu" "F.Mask" "F.Paste")
		)
		(pad "C-6" smd rect
			(at -25.83625 8.62381)
			(size 1.54991 0.24994)
			(layers "F.Cu" "F.Mask" "F.Paste")
		)
		(pad "C-7" smd rect
			(at -21.78647 8.12368)
			(size 1.54991 0.24994)
			(layers "F.Cu" "F.Mask" "F.Paste")
		)
		(pad "C-8" smd rect
			(at -25.83625 8.12368)
			(size 1.54991 0.24994)
			(layers "F.Cu" "F.Mask" "F.Paste")
		)
		(pad "C-9" smd rect
			(at -21.78647 7.62381)
			(size 1.54991 0.24994)
			(layers "F.Cu" "F.Mask" "F.Paste")
			(net "GND")
		)
		(pad "C-10" smd rect
			(at -25.83625 7.62381)
			(size 1.54991 0.24994)
			(layers "F.Cu" "F.Mask" "F.Paste")
			(net "GND")
		)
		(pad "C-11" smd rect
			(at -21.78647 7.12368)
			(size 1.54991 0.24994)
			(layers "F.Cu" "F.Mask" "F.Paste")
		)
		(pad "C-12" smd rect
			(at -25.83625 7.12368)
			(size 1.54991 0.24994)
			(layers "F.Cu" "F.Mask" "F.Paste")
		)
		(pad "C-13" smd rect
			(at -21.78647 6.62381)
			(size 1.54991 0.24994)
			(layers "F.Cu" "F.Mask" "F.Paste")
		)
		(pad "C-14" smd rect
			(at -25.83625 6.62381)
			(size 1.54991 0.24994)
			(layers "F.Cu" "F.Mask" "F.Paste")
		)
		(pad "C-15" smd rect
			(at -21.78647 6.12369)
			(size 1.54991 0.24994)
			(layers "F.Cu" "F.Mask" "F.Paste")
		)
		(pad "C-16" smd rect
			(at -25.83625 6.12369)
			(size 1.54991 0.24994)
			(layers "F.Cu" "F.Mask" "F.Paste")
		)
		(pad "C-17" smd rect
			(at -21.78647 5.62381)
			(size 1.54991 0.24994)
			(layers "F.Cu" "F.Mask" "F.Paste")
		)
		(pad "C-18" smd rect
			(at -25.83625 5.62381)
			(size 1.54991 0.24994)
			(layers "F.Cu" "F.Mask" "F.Paste")
		)
		(pad "C-19" smd rect
			(at -21.78647 5.12369)
			(size 1.54991 0.24994)
			(layers "F.Cu" "F.Mask" "F.Paste")
			(net "GND")
		)
		(pad "C-20" smd rect
			(at -25.83625 5.12369)
			(size 1.54991 0.24994)
			(layers "F.Cu" "F.Mask" "F.Paste")
			(net "GND")
		)
		(pad "C-21" smd rect
			(at -21.78647 4.62382)
			(size 1.54991 0.24994)
			(layers "F.Cu" "F.Mask" "F.Paste")
			(net "PCIE_PERST")
		)
		(pad "C-22" smd rect
			(at -25.83625 4.62382)
			(size 1.54991 0.24994)
			(layers "F.Cu" "F.Mask" "F.Paste")
		)
		(pad "C-23" smd rect
			(at -21.78647 4.12369)
			(size 1.54991 0.24994)
			(layers "F.Cu" "F.Mask" "F.Paste")
			(net "KEY1")
		)
		(pad "C-24" smd rect
			(at -25.83625 4.12369)
			(size 1.54991 0.24994)
			(layers "F.Cu" "F.Mask" "F.Paste")
		)
		(pad "C-25" smd rect
			(at -21.78647 3.62382)
			(size 1.54991 0.24994)
			(layers "F.Cu" "F.Mask" "F.Paste")
		)
		(pad "C-26" smd rect
			(at -25.83625 3.62382)
			(size 1.54991 0.24994)
			(layers "F.Cu" "F.Mask" "F.Paste")
		)
		(pad "C-27" smd rect
			(at -21.78647 3.12369)
			(size 1.54991 0.24994)
			(layers "F.Cu" "F.Mask" "F.Paste")
		)
		(pad "C-28" smd rect
			(at -25.83625 3.12369)
			(size 1.54991 0.24994)
			(layers "F.Cu" "F.Mask" "F.Paste")
		)
		(pad "C-29" smd rect
			(at -21.78647 2.62382)
			(size 1.54991 0.24994)
			(layers "F.Cu" "F.Mask" "F.Paste")
			(net "GND")
		)
		(pad "C-30" smd rect
			(at -25.83625 2.62382)
			(size 1.54991 0.24994)
			(layers "F.Cu" "F.Mask" "F.Paste")
			(net "GND")
		)
		(pad "C-31" smd rect
			(at -21.78647 2.12369)
			(size 1.54991 0.24994)
			(layers "F.Cu" "F.Mask" "F.Paste")
		)
		(pad "C-32" smd rect
			(at -25.83625 2.12369)
			(size 1.54991 0.24994)
			(layers "F.Cu" "F.Mask" "F.Paste")
		)
		(pad "C-33" smd rect
			(at -21.78647 1.62382)
			(size 1.54991 0.24994)
			(layers "F.Cu" "F.Mask" "F.Paste")
		)
		(pad "C-34" smd rect
			(at -25.83625 1.62382)
			(size 1.54991 0.24994)
			(layers "F.Cu" "F.Mask" "F.Paste")
		)
		(pad "C-35" smd rect
			(at -21.78647 1.1237)
			(size 1.54991 0.24994)
			(layers "F.Cu" "F.Mask" "F.Paste")
		)
		(pad "C-36" smd rect
			(at -25.83625 1.1237)
			(size 1.54991 0.24994)
			(layers "F.Cu" "F.Mask" "F.Paste")
		)
		(pad "C-37" smd rect
			(at -21.78647 0.62382)
			(size 1.54991 0.24994)
			(layers "F.Cu" "F.Mask" "F.Paste")
		)
		(pad "C-38" smd rect
			(at -25.83625 0.62382)
			(size 1.54991 0.24994)
			(layers "F.Cu" "F.Mask" "F.Paste")
		)
		(pad "C-39" smd rect
			(at -21.78647 0.1237)
			(size 1.54991 0.24994)
			(layers "F.Cu" "F.Mask" "F.Paste")
			(net "GND")
		)
		(pad "C-40" smd rect
			(at -25.83625 0.1237)
			(size 1.54991 0.24994)
			(layers "F.Cu" "F.Mask" "F.Paste")
			(net "GND")
		)
		(pad "C-41" smd rect
			(at -21.78647 -0.37617)
			(size 1.54991 0.24994)
			(layers "F.Cu" "F.Mask" "F.Paste")
		)
		(pad "C-42" smd rect
			(at -25.83625 -0.37617)
			(size 1.54991 0.24994)
			(layers "F.Cu" "F.Mask" "F.Paste")
		)
		(pad "C-43" smd rect
			(at -21.78647 -0.8763)
			(size 1.54991 0.24994)
			(layers "F.Cu" "F.Mask" "F.Paste")
		)
		(pad "C-44" smd rect
			(at -25.83625 -0.8763)
			(size 1.54991 0.24994)
			(layers "F.Cu" "F.Mask" "F.Paste")
		)
		(pad "C-45" smd rect
			(at -21.78647 -1.37617)
			(size 1.54991 0.24994)
			(layers "F.Cu" "F.Mask" "F.Paste")
		)
		(pad "C-46" smd rect
			(at -25.83625 -1.37617)
			(size 1.54991 0.24994)
			(layers "F.Cu" "F.Mask" "F.Paste")
		)
		(pad "C-47" smd rect
			(at -21.78647 -1.8763)
			(size 1.54991 0.24994)
			(layers "F.Cu" "F.Mask" "F.Paste")
		)
		(pad "C-48" smd rect
			(at -25.83625 -1.8763)
			(size 1.54991 0.24994)
			(layers "F.Cu" "F.Mask" "F.Paste")
		)
		(pad "C-49" smd rect
			(at -21.78647 -2.37617)
			(size 1.54991 0.24994)
			(layers "F.Cu" "F.Mask" "F.Paste")
			(net "GND")
		)
		(pad "C-50" smd rect
			(at -25.83625 -2.37617)
			(size 1.54991 0.24994)
			(layers "F.Cu" "F.Mask" "F.Paste")
			(net "GND")
		)
		(pad "C-51" smd rect
			(at -21.78647 -2.8763)
			(size 1.54991 0.24994)
			(layers "F.Cu" "F.Mask" "F.Paste")
		)
		(pad "C-52" smd rect
			(at -25.83625 -2.8763)
			(size 1.54991 0.24994)
			(layers "F.Cu" "F.Mask" "F.Paste")
		)
		(pad "C-53" smd rect
			(at -21.78647 -3.37617)
			(size 1.54991 0.24994)
			(layers "F.Cu" "F.Mask" "F.Paste")
		)
		(pad "C-54" smd rect
			(at -25.83625 -3.37617)
			(size 1.54991 0.24994)
			(layers "F.Cu" "F.Mask" "F.Paste")
		)
		(pad "C-55" smd rect
			(at -21.78647 -3.87629)
			(size 1.54991 0.24994)
			(layers "F.Cu" "F.Mask" "F.Paste")
		)
		(pad "C-56" smd rect
			(at -25.83625 -3.87629)
			(size 1.54991 0.24994)
			(layers "F.Cu" "F.Mask" "F.Paste")
		)
		(pad "C-57" smd rect
			(at -21.78647 -4.37617)
			(size 1.54991 0.24994)
			(layers "F.Cu" "F.Mask" "F.Paste")
		)
		(pad "C-58" smd rect
			(at -25.83625 -4.37617)
			(size 1.54991 0.24994)
			(layers "F.Cu" "F.Mask" "F.Paste")
		)
		(pad "C-59" smd rect
			(at -21.78647 -4.87629)
			(size 1.54991 0.24994)
			(layers "F.Cu" "F.Mask" "F.Paste")
			(net "GND")
		)
		(pad "C-60" smd rect
			(at -25.83625 -4.87629)
			(size 1.54991 0.24994)
			(layers "F.Cu" "F.Mask" "F.Paste")
			(net "GND")
		)
		(pad "C-61" smd rect
			(at -21.78647 -5.37616)
			(size 1.54991 0.24994)
			(layers "F.Cu" "F.Mask" "F.Paste")
		)
		(pad "C-62" smd rect
			(at -25.83625 -5.37616)
			(size 1.54991 0.24994)
			(layers "F.Cu" "F.Mask" "F.Paste")
		)
		(pad "C-63" smd rect
			(at -21.78647 -5.87629)
			(size 1.54991 0.24994)
			(layers "F.Cu" "F.Mask" "F.Paste")
		)
		(pad "C-64" smd rect
			(at -25.83625 -5.87629)
			(size 1.54991 0.24994)
			(layers "F.Cu" "F.Mask" "F.Paste")
		)
		(pad "C-65" smd rect
			(at -21.78647 -6.37616)
			(size 1.54991 0.24994)
			(layers "F.Cu" "F.Mask" "F.Paste")
		)
		(pad "C-66" smd rect
			(at -25.83625 -6.37616)
			(size 1.54991 0.24994)
			(layers "F.Cu" "F.Mask" "F.Paste")
		)
		(pad "C-67" smd rect
			(at -21.78647 -6.87629)
			(size 1.54991 0.24994)
			(layers "F.Cu" "F.Mask" "F.Paste")
		)
		(pad "C-68" smd rect
			(at -25.83625 -6.87629)
			(size 1.54991 0.24994)
			(layers "F.Cu" "F.Mask" "F.Paste")
		)
		(pad "C-69" smd rect
			(at -21.78647 -7.37616)
			(size 1.54991 0.24994)
			(layers "F.Cu" "F.Mask" "F.Paste")
			(net "GND")
		)
		(pad "C-70" smd rect
			(at -25.83625 -7.37616)
			(size 1.54991 0.24994)
			(layers "F.Cu" "F.Mask" "F.Paste")
			(net "GND")
		)
		(pad "C-71" smd rect
			(at -21.78647 -7.87629)
			(size 1.54991 0.24994)
			(layers "F.Cu" "F.Mask" "F.Paste")
		)
		(pad "C-72" smd rect
			(at -25.83625 -7.87629)
			(size 1.54991 0.24994)
			(layers "F.Cu" "F.Mask" "F.Paste")
		)
		(pad "C-73" smd rect
			(at -21.78647 -8.37616)
			(size 1.54991 0.24994)
			(layers "F.Cu" "F.Mask" "F.Paste")
		)
		(pad "C-74" smd rect
			(at -25.83625 -8.37616)
			(size 1.54991 0.24994)
			(layers "F.Cu" "F.Mask" "F.Paste")
		)
		(pad "C-75" smd rect
			(at -21.78647 -8.87628)
			(size 1.54991 0.24994)
			(layers "F.Cu" "F.Mask" "F.Paste")
		)
		(pad "C-76" smd rect
			(at -25.83625 -8.87628)
			(size 1.54991 0.24994)
			(layers "F.Cu" "F.Mask" "F.Paste")
		)
		(pad "C-77" smd rect
			(at -21.78647 -9.37616)
			(size 1.54991 0.24994)
			(layers "F.Cu" "F.Mask" "F.Paste")
			(net "FPGA_TCK")
		)
		(pad "C-78" smd rect
			(at -25.83625 -9.37616)
			(size 1.54991 0.24994)
			(layers "F.Cu" "F.Mask" "F.Paste")
			(net "FPGA_TDI")
		)
		(pad "C-79" smd rect
			(at -21.78647 -9.87628)
			(size 1.54991 0.24994)
			(layers "F.Cu" "F.Mask" "F.Paste")
			(net "FPGA_TDO")
		)
		(pad "C-80" smd rect
			(at -25.83625 -9.87628)
			(size 1.54991 0.24994)
			(layers "F.Cu" "F.Mask" "F.Paste")
			(net "FPGA_TMS")
		)
		(pad "C-81" smd rect
			(at -23.8 11.05)
			(size 1.70002 1.35001)
			(layers "F.Cu" "F.Mask" "F.Paste")
		)
		(pad "C-82" thru_hole circle
			(at -23.81136 9.87374)
			(size 0.55016 0.55016)
			(drill 0.55016)
			(layers "*.Cu" "*.Mask")
			(remove_unused_layers no)
			(thermal_bridge_angle 90)
		)
		(pad "C-83" thru_hole circle
			(at -23.81136 -10.12622)
			(size 0.55016 0.55016)
			(drill 0.55016)
			(layers "*.Cu" "*.Mask")
			(remove_unused_layers no)
			(thermal_bridge_angle 90)
		)
		(pad "C-84" smd rect
			(at -23.8 -11.3)
			(size 1.70002 1.35001)
			(layers "F.Cu" "F.Mask" "F.Paste")
		)
		(pad "D-1" smd rect
			(at 8.79894 16.77035)
			(size 0.24994 1.54991)
			(layers "F.Cu" "F.Mask" "F.Paste")
		)
		(pad "D-2" smd rect
			(at 8.79894 20.82013)
			(size 0.24994 1.54991)
			(layers "F.Cu" "F.Mask" "F.Paste")
		)
		(pad "D-3" smd rect
			(at 8.29881 16.77035)
			(size 0.24994 1.54991)
			(layers "F.Cu" "F.Mask" "F.Paste")
		)
		(pad "D-4" smd rect
			(at 8.29881 20.82013)
			(size 0.24994 1.54991)
			(layers "F.Cu" "F.Mask" "F.Paste")
		)
		(pad "D-5" smd rect
			(at 7.79894 16.77035)
			(size 0.24994 1.54991)
			(layers "F.Cu" "F.Mask" "F.Paste")
		)
		(pad "D-6" smd rect
			(at 7.79894 20.82013)
			(size 0.24994 1.54991)
			(layers "F.Cu" "F.Mask" "F.Paste")
		)
		(pad "D-7" smd rect
			(at 7.29882 16.77035)
			(size 0.24994 1.54991)
			(layers "F.Cu" "F.Mask" "F.Paste")
		)
		(pad "D-8" smd rect
			(at 7.29882 20.82013)
			(size 0.24994 1.54991)
			(layers "F.Cu" "F.Mask" "F.Paste")
		)
		(pad "D-9" smd rect
			(at 6.79894 16.77035)
			(size 0.24994 1.54991)
			(layers "F.Cu" "F.Mask" "F.Paste")
			(net "GND")
		)
		(pad "D-10" smd rect
			(at 6.79894 20.82013)
			(size 0.24994 1.54991)
			(layers "F.Cu" "F.Mask" "F.Paste")
			(net "GND")
		)
		(pad "D-11" smd rect
			(at 6.29882 16.77035)
			(size 0.24994 1.54991)
			(layers "F.Cu" "F.Mask" "F.Paste")
		)
		(pad "D-12" smd rect
			(at 6.29882 20.82013)
			(size 0.24994 1.54991)
			(layers "F.Cu" "F.Mask" "F.Paste")
			(net "PCIE_TX2_P")
		)
		(pad "D-13" smd rect
			(at 5.79895 16.77035)
			(size 0.24994 1.54991)
			(layers "F.Cu" "F.Mask" "F.Paste")
		)
		(pad "D-14" smd rect
			(at 5.79895 20.82013)
			(size 0.24994 1.54991)
			(layers "F.Cu" "F.Mask" "F.Paste")
			(net "PCIE_TX2_N")
		)
		(pad "D-15" smd rect
			(at 5.29882 16.77035)
			(size 0.24994 1.54991)
			(layers "F.Cu" "F.Mask" "F.Paste")
			(net "GND")
		)
		(pad "D-16" smd rect
			(at 5.29882 20.82013)
			(size 0.24994 1.54991)
			(layers "F.Cu" "F.Mask" "F.Paste")
		)
	)
)
